# TIMECARD (Time Appliance Project (Time Card)) — schematic netlist excerpt (pin names and nets, part order shuffled) for the footprints in the layout excerpt that follows; sources: Cadence DE-HDL packaged netlist, KiCad conversion of R4006-B0001-02_R01.brd

SP65  NULL  pkg DUMMY  page 34

J17  CONN_HDR_2X2_M_S_SMT  pkg S_M_H_2X2_S_P100_V3  page 16
  \1\  = SN_EEPROM_WP
  \2\  = SG
  \3\  = SEC_EEPROM_WP
  \4\  = SG

R9  RESISTOR  49.9OHM 1%  pkg SMC_0603R_H022  page 27 : \1\ = XP12R0V_IN ; \2\ = XP12R0V_A_AVIN

(kicad_pcb
	(version 20260206)
	(generator "pcbnew")
	(generator_version "10.0")
	(general
		(thickness 1.6)
		(legacy_teardrops no)
	)
	(paper "A4")
	(title_block
		(title "timecard-production-celestica-r4006 — R4006-B0001-02_R01.brd")
		(comment 1 "Time Appliance Project (Time Card) / footprints 463-465 of 1113")
	)
	(layers
		(0 "F.Cu" signal "TOP")
		(4 "In1.Cu" signal "L02_GND1")
		(6 "In2.Cu" signal "L03_SIG1")
		(8 "In3.Cu" signal "L04_GND2")
		(10 "In4.Cu" signal "L05_VCC1")
		(12 "In5.Cu" signal "L06_VCC2")
		(14 "In6.Cu" signal "L07_GND3")
		(16 "In7.Cu" signal "L08_SIG2")
		(18 "In8.Cu" signal "L09_GND4")
		(2 "B.Cu" signal "BOTTOM")
		(9 "F.Adhes" user "F.Adhesive")
		(11 "B.Adhes" user "B.Adhesive")
		(13 "F.Paste" user "Package Geometry/Pastemask Top")
		(15 "B.Paste" user "Package Geometry/Pastemask Bottom")
		(5 "F.SilkS" user "Ref Des/Silkscreen Top")
		(7 "B.SilkS" user "Ref Des/Silkscreen Bottom")
		(1 "F.Mask" user "Board Geometry/Soldermask Top")
		(3 "B.Mask" user "Board Geometry/Soldermask Bottom")
		(17 "Dwgs.User" user "User.Drawings")
		(19 "Cmts.User" user "User.Comments")
		(21 "Eco1.User" user "User.Eco1")
		(23 "Eco2.User" user "User.Eco2")
		(25 "Edge.Cuts" user "Board Geometry/Outline")
		(27 "Margin" user)
		(31 "F.CrtYd" user "Package Geometry/Place Bound Top")
		(29 "B.CrtYd" user "Package Geometry/Place Bound Bottom")
		(35 "F.Fab" user "Ref Des/Assembly Top")
		(33 "B.Fab" user "Ref Des/Assembly Bottom")
	)
	(footprint ""
		(layer "F.Cu")
		(at 84.836 -71.501 90)
		(property "Reference" "J17"
			(at 3.38963 -0.762 0)
			(unlocked yes)
			(layer "F.SilkS")
			(effects
				(font
					(size 0.7874 0.5842)
					(thickness 0.1524)
				)
			)
		)
		(property "Value" ""
			(at 0 0 90)
			(layer "F.Fab")
			(effects
				(font
					(size 1.27 1.27)
				)
			)
		)
		(property "Device Type" "CONN_HDR_2X2_M_S_SMT-G200-1068A"
			(at 0.069088 6.518656 90)
			(unlocked yes)
			(layer "F.Fab")
			(hide yes)
			(effects
				(font
					(size 0.7874 0.5842)
					(thickness 0.000001)
				)
			)
		)
		(property "User Part Number" "PARTNUM*"
			(at 0.069088 7.712456 90)
			(unlocked yes)
			(layer "Cmts.User")
			(hide yes)
			(effects
				(font
					(size 0.7874 0.5842)
					(thickness 0.000001)
				)
			)
		)
		(duplicate_pad_numbers_are_jumpers no)
		(fp_line
			(start 2.589022 -4.637024)
			(end 2.589022 4.637024)
			(stroke
				(width 0.1)
				(type default)
			)
			(layer "F.SilkS")
		)
		(fp_line
			(start -2.589022 -4.637024)
			(end 2.589022 -4.637024)
			(stroke
				(width 0.1)
				(type default)
			)
			(layer "F.SilkS")
		)
		(fp_line
			(start 2.589022 4.637024)
			(end -2.589022 4.637024)
			(stroke
				(width 0.1)
				(type default)
			)
			(layer "F.SilkS")
		)
		(fp_line
			(start -2.589022 4.637024)
			(end -2.589022 -4.637024)
			(stroke
				(width 0.1)
				(type default)
			)
			(layer "F.SilkS")
		)
		(fp_rect
			(start -2.843022 4.891024)
			(end 2.843022 -4.891024)
			(stroke
				(width 0)
				(type default)
			)
			(fill no)
			(layer "F.CrtYd")
		)
		(fp_line
			(start 2.335022 -2.439924)
			(end -2.335022 -2.439924)
			(stroke
				(width 0.1)
				(type default)
			)
			(layer "F.Fab")
		)
		(fp_line
			(start -2.335022 -2.439924)
			(end -2.335022 2.439924)
			(stroke
				(width 0.1)
				(type default)
			)
			(layer "F.Fab")
		)
		(fp_line
			(start 2.335022 2.439924)
			(end 2.335022 -2.439924)
			(stroke
				(width 0.1)
				(type default)
			)
			(layer "F.Fab")
		)
		(fp_line
			(start -2.335022 2.439924)
			(end 2.335022 2.439924)
			(stroke
				(width 0.1)
				(type default)
			)
			(layer "F.Fab")
		)
		(fp_text user "4"
			(at 2.11963 -5.4991 0)
			(unlocked yes)
			(layer "F.SilkS")
			(effects
				(font
					(size 0.7874 0.5842)
					(thickness 0.1524)
				)
				(justify left)
			)
		)
		(fp_text user "2"
			(at -0.29337 -5.4991 0)
			(unlocked yes)
			(layer "F.SilkS")
			(effects
				(font
					(size 0.7874 0.5842)
					(thickness 0.1524)
				)
				(justify left)
			)
		)
		(fp_text user "3"
			(at 3.13563 3.0099 0)
			(unlocked yes)
			(layer "F.SilkS")
			(effects
				(font
					(size 0.7874 0.5842)
					(thickness 0.1524)
				)
				(justify left)
			)
		)
		(fp_text user "1"
			(at -0.42037 4.7879 0)
			(unlocked yes)
			(layer "F.SilkS")
			(effects
				(font
					(size 0.7874 0.5842)
					(thickness 0.1524)
				)
				(justify left)
			)
		)
		(fp_text user "4"
			(at 1.109218 -3.767074 0)
			(unlocked yes)
			(layer "F.Fab")
			(effects
				(font
					(size 0.7874 0.5842)
					(thickness 0.1524)
				)
				(justify left)
			)
		)
		(fp_text user "2"
			(at -1.667002 -3.7338 0)
			(unlocked yes)
			(layer "F.Fab")
			(effects
				(font
					(size 0.7874 0.5842)
					(thickness 0.1524)
				)
				(justify left)
			)
		)
		(fp_text user "3"
			(at 1.26111 2.939542 0)
			(unlocked yes)
			(layer "F.Fab")
			(effects
				(font
					(size 0.7874 0.5842)
					(thickness 0.1524)
				)
				(justify left)
			)
		)
		(fp_text user "1"
			(at -1.38049 2.939542 0)
			(unlocked yes)
			(layer "F.Fab")
			(effects
				(font
					(size 0.7874 0.5842)
					(thickness 0.1524)
				)
				(justify left)
			)
		)
		(pad "1" smd rect
			(at -1.27 2.605024 90)
			(size 1.27 3.556)
			(layers "F.Cu" "F.Mask" "F.Paste")
			(net "SN_EEPROM_WP")
		)
		(pad "2" smd rect
			(at -1.27 -2.605024 90)
			(size 1.27 3.556)
			(layers "F.Cu" "F.Mask" "F.Paste")
			(net "SG")
		)
		(pad "3" smd rect
			(at 1.27 2.605024 90)
			(size 1.27 3.556)
			(layers "F.Cu" "F.Mask" "F.Paste")
			(net "SEC_EEPROM_WP")
		)
		(pad "4" smd rect
			(at 1.27 -2.605024 90)
			(size 1.27 3.556)
			(layers "F.Cu" "F.Mask" "F.Paste")
			(net "SG")
		)
	)
	(footprint ""
		(layer "F.Cu")
		(at 44.069 -130.429)
		(property "Reference" "SP65"
			(at 0 0 0)
			(layer "F.SilkS")
			(hide yes)
			(effects
				(font
					(size 1.27 1.27)
				)
			)
		)
		(property "Value" ""
			(at 0 0 0)
			(layer "F.Fab")
			(effects
				(font
					(size 1.27 1.27)
				)
			)
		)
		(duplicate_pad_numbers_are_jumpers no)
	)
	(footprint ""
		(layer "F.Cu")
		(at 135.6614 -99.1108)
		(property "Reference" "R9"
			(at -2.5654 -0.29083 0)
			(unlocked yes)
			(layer "F.SilkS")
			(effects
				(font
					(size 0.7874 0.5842)
					(thickness 0.1524)
				)
			)
		)
		(property "Value" "VAL*"
			(at 0.0508 2.549906 0)
			(unlocked yes)
			(layer "F.Fab")
			(hide yes)
			(effects
				(font
					(size 0.7874 0.5842)
					(thickness 0.1524)
				)
			)
		)
		(property "Device Type" "RESISTOR-G156-049R9-01,49.9OHMA"
			(at 0.0254 1.584706 0)
			(unlocked yes)
			(layer "F.Fab")
			(hide yes)
			(effects
				(font
					(size 0.7874 0.5842)
					(thickness 0.1524)
				)
			)
		)
		(property "User Part Number" "PARTNUM*"
			(at 0.0762 4.480306 0)
			(unlocked yes)
			(layer "Cmts.User")
			(hide yes)
			(effects
				(font
					(size 0.7874 0.5842)
					(thickness 0.1524)
				)
			)
		)
		(property "Tolerance" "TOL*"
			(at 0.0508 3.515106 0)
			(unlocked yes)
			(layer "Cmts.User")
			(hide yes)
			(effects
				(font
					(size 0.7874 0.5842)
					(thickness 0.1524)
				)
			)
		)
		(duplicate_pad_numbers_are_jumpers no)
		(fp_line
			(start -1.3208 -0.7112)
			(end 1.3208 -0.7112)
			(stroke
				(width 0.1)
				(type default)
			)
			(layer "F.SilkS")
		)
		(fp_line
			(start -1.3208 0.7112)
			(end -1.3208 -0.7112)
			(stroke
				(width 0.1)
				(type default)
			)
			(layer "F.SilkS")
		)
		(fp_line
			(start 1.3208 -0.7112)
			(end 1.3208 0.7112)
			(stroke
				(width 0.1)
				(type default)
			)
			(layer "F.SilkS")
		)
		(fp_line
			(start 1.3208 0.7112)
			(end -1.3208 0.7112)
			(stroke
				(width 0.1)
				(type default)
			)
			(layer "F.SilkS")
		)
		(fp_rect
			(start -1.3208 0.7112)
			(end 1.3208 -0.7112)
			(stroke
				(width 0)
				(type default)
			)
			(fill no)
			(layer "F.CrtYd")
		)
		(fp_line
			(start -0.8128 -0.4572)
			(end 0.8128 -0.4572)
			(stroke
				(width 0.1)
				(type default)
			)
			(layer "F.Fab")
		)
		(fp_line
			(start -0.8128 0.4572)
			(end -0.8128 -0.4572)
			(stroke
				(width 0.1)
				(type default)
			)
			(layer "F.Fab")
		)
		(fp_line
			(start 0.8128 -0.4572)
			(end 0.8128 0.4572)
			(stroke
				(width 0.1)
				(type default)
			)
			(layer "F.Fab")
		)
		(fp_line
			(start 0.8128 0.4572)
			(end -0.8128 0.4572)
			(stroke
				(width 0.1)
				(type default)
			)
			(layer "F.Fab")
		)
		(pad "1" smd rect
			(at -0.6858 0)
			(size 0.762 0.8636)
			(layers "F.Cu" "F.Mask" "F.Paste")
			(net "XP12R0V_IN")
		)
		(pad "2" smd rect
			(at 0.6858 0)
			(size 0.762 0.8636)
			(layers "F.Cu" "F.Mask" "F.Paste")
			(net "XP12R0V_A_AVIN")
		)
		(zone
			(layer "F.Cu")
			(hatch none 0.5)
			(connect_pads
				(clearance 0)
			)
			(min_thickness 0.25)
			(keepout
				(tracks allowed)
				(vias not_allowed)
				(pads allowed)
				(copperpour not_allowed)
				(footprints allowed)
			)
			(placement
				(enabled no)
				(sheetname "")
			)
			(fill
				(thermal_gap 0.5)
				(thermal_bridge_width 0.5)
				(island_removal_mode 0)
			)
			(polygon
				(pts
					(xy 135.509 -98.6536) (xy 135.8138 -98.6536) (xy 135.8138 -99.568) (xy 135.509 -99.568)
				)
			)
		)
	)
)
